(kicad_pcb
	(version 20260206)
	(generator "pcbnew")
	(generator_version "10.0")
	(general
		(thickness 1.6)
		(legacy_teardrops no)
	)
	(paper "A4")
	(title_block
		(title "Bryce Canyon_Front Panel_16369-1_OCP.brd")
		(comment 1 "Bryce Canyon / footprints 122-128 of 154")
	)
	(layers
		(0 "F.Cu" signal "TOP")
		(4 "In1.Cu" signal "L2GND")
		(6 "In2.Cu" signal "L3VCC")
		(2 "B.Cu" signal "BOTTOM")
		(9 "F.Adhes" user "F.Adhesive")
		(11 "B.Adhes" user "B.Adhesive")
		(13 "F.Paste" user "Package Geometry/Pastemask Top")
		(15 "B.Paste" user "Package Geometry/Pastemask Bottom")
		(5 "F.SilkS" user "Ref Des/Silkscreen Top")
		(7 "B.SilkS" user "Ref Des/Silkscreen Bottom")
		(1 "F.Mask" user "Board Geometry/Soldermask Top")
		(3 "B.Mask" user "Board Geometry/Soldermask Bottom")
		(17 "Dwgs.User" user "User.Drawings")
		(19 "Cmts.User" user "User.Comments")
		(21 "Eco1.User" user "User.Eco1")
		(23 "Eco2.User" user "User.Eco2")
		(25 "Edge.Cuts" user "Board Geometry/Outline")
		(27 "Margin" user)
		(31 "F.CrtYd" user "Package Geometry/Place Bound Top")
		(29 "B.CrtYd" user "Package Geometry/Place Bound Bottom")
		(35 "F.Fab" user "Ref Des/Assembly Top")
		(33 "B.Fab" user "Ref Des/Assembly Bottom")
	)
	(footprint ""
		(layer "F.Cu")
		(at 48.951896 -20.07362)
		(property "Reference" "C23"
			(at 0 0 0)
			(layer "F.SilkS")
			(hide yes)
			(effects
				(font
					(size 1.27 1.27)
				)
			)
		)
		(property "Value" "SCD1U16V2KX-3GP"
			(at 1.1811 -2.7051 0)
			(unlocked yes)
			(layer "F.Fab")
			(hide yes)
			(effects
				(font
					(size 1.016 1.016)
					(thickness 0.1524)
				)
			)
		)
		(property "Device Type" "C402H22"
			(at 1.1811 -4.2291 0)
			(unlocked yes)
			(layer "F.Fab")
			(hide yes)
			(effects
				(font
					(size 1.016 1.016)
					(thickness 0.1524)
				)
			)
		)
		(duplicate_pad_numbers_are_jumpers no)
		(fp_rect
			(start -0.4318 0.9525)
			(end 0.4318 -0.9525)
			(stroke
				(width 0)
				(type default)
			)
			(fill no)
			(layer "F.CrtYd")
		)
		(fp_rect
			(start -0.4318 0.9525)
			(end 0.4318 -0.9525)
			(stroke
				(width 0)
				(type default)
			)
			(fill no)
			(layer "F.Fab")
		)
		(pad "1" smd custom
			(at 0 -0.4445)
			(size 0.1524 0.1524)
			(layers "F.Cu" "F.Mask" "F.Paste")
			(net "P3V3_STBY_B")
			(options
				(clearance outline)
				(anchor circle)
			)
			(primitives
				(gr_poly
					(pts
						(arc
							(start 0.3048 -0.2032)
							(mid 0.275042 -0.275042)
							(end 0.2032 -0.3048)
						)
						(arc
							(start -0.2032 -0.3048)
							(mid -0.275042 -0.275042)
							(end -0.3048 -0.2032)
						)
						(arc
							(start -0.3048 0.2032)
							(mid -0.275042 0.275042)
							(end -0.2032 0.3048)
						)
						(arc
							(start 0.2032 0.3048)
							(mid 0.275042 0.275042)
							(end 0.3048 0.2032)
						)
					)
					(width 0)
					(fill yes)
				)
			)
		)
		(pad "2" smd custom
			(at 0 0.4445)
			(size 0.1524 0.1524)
			(layers "F.Cu" "F.Mask" "F.Paste")
			(net "GND")
			(options
				(clearance outline)
				(anchor circle)
			)
			(primitives
				(gr_poly
					(pts
						(arc
							(start 0.3048 -0.2032)
							(mid 0.275042 -0.275042)
							(end 0.2032 -0.3048)
						)
						(arc
							(start -0.2032 -0.3048)
							(mid -0.275042 -0.275042)
							(end -0.3048 -0.2032)
						)
						(arc
							(start -0.3048 0.2032)
							(mid -0.275042 0.275042)
							(end -0.2032 0.3048)
						)
						(arc
							(start 0.2032 0.3048)
							(mid 0.275042 0.275042)
							(end 0.3048 0.2032)
						)
					)
					(width 0)
					(fill yes)
				)
			)
		)
	)
	(footprint ""
		(layer "F.Cu")
		(at 52.197 -12.827)
		(property "Reference" "R14"
			(at 0 0 0)
			(layer "F.SilkS")
			(hide yes)
			(effects
				(font
					(size 1.27 1.27)
				)
			)
		)
		(property "Value" "0R2J-2-GP"
			(at 0.064008 -4.679696 0)
			(unlocked yes)
			(layer "F.Fab")
			(hide yes)
			(effects
				(font
					(size 2.54 2.54)
					(thickness 0.381)
				)
			)
		)
		(property "Device Type" "R402H16"
			(at 0.064008 -6.203696 0)
			(unlocked yes)
			(layer "F.Fab")
			(hide yes)
			(effects
				(font
					(size 2.54 2.54)
					(thickness 0.381)
				)
			)
		)
		(duplicate_pad_numbers_are_jumpers no)
		(fp_line
			(start -0.508 -0.9398)
			(end -0.508 0.9398)
			(stroke
				(width 0.1524)
				(type default)
			)
			(layer "F.SilkS")
		)
		(fp_line
			(start 0.508 -0.9398)
			(end -0.508 -0.9398)
			(stroke
				(width 0.1524)
				(type default)
			)
			(layer "F.SilkS")
		)
		(fp_rect
			(start -0.508 0.9398)
			(end 0.508 -0.9398)
			(stroke
				(width 0)
				(type default)
			)
			(fill no)
			(layer "F.CrtYd")
		)
		(fp_rect
			(start -0.508 0.9398)
			(end 0.508 -0.9398)
			(stroke
				(width 0)
				(type default)
			)
			(fill no)
			(layer "F.Fab")
		)
		(pad "1" smd custom
			(at 0 -0.4445)
			(size 0.1397 0.1397)
			(layers "F.Cu" "F.Mask" "F.Paste")
			(net "I2C_DEBUG_B_SCL_R")
			(options
				(clearance outline)
				(anchor circle)
			)
			(primitives
				(gr_poly
					(pts
						(arc
							(start -0.1778 -0.2794)
							(mid -0.249642 -0.249642)
							(end -0.2794 -0.1778)
						)
						(arc
							(start -0.2794 0.1778)
							(mid -0.249642 0.249642)
							(end -0.1778 0.2794)
						)
						(arc
							(start 0.1778 0.2794)
							(mid 0.249642 0.249642)
							(end 0.2794 0.1778)
						)
						(arc
							(start 0.2794 -0.1778)
							(mid 0.249642 -0.249642)
							(end 0.1778 -0.2794)
						)
					)
					(width 0)
					(fill yes)
				)
			)
		)
		(pad "2" smd custom
			(at 0 0.4445)
			(size 0.1397 0.1397)
			(layers "F.Cu" "F.Mask" "F.Paste")
			(net "I2C_DEBUG_B_SCL_L")
			(options
				(clearance outline)
				(anchor circle)
			)
			(primitives
				(gr_poly
					(pts
						(arc
							(start -0.1778 -0.2794)
							(mid -0.249642 -0.249642)
							(end -0.2794 -0.1778)
						)
						(arc
							(start -0.2794 0.1778)
							(mid -0.249642 0.249642)
							(end -0.1778 0.2794)
						)
						(arc
							(start 0.1778 0.2794)
							(mid 0.249642 0.249642)
							(end 0.2794 0.1778)
						)
						(arc
							(start 0.2794 -0.1778)
							(mid 0.249642 -0.249642)
							(end 0.1778 -0.2794)
						)
					)
					(width 0)
					(fill yes)
				)
			)
		)
	)
	(footprint ""
		(layer "F.Cu")
		(at 49.395634 -30.861 -90)
		(property "Reference" "R52"
			(at 0 0 270)
			(layer "F.SilkS")
			(hide yes)
			(effects
				(font
					(size 1.27 1.27)
				)
			)
		)
		(property "Value" "1KR2F-3-GP"
			(at 0.064008 -4.679696 270)
			(unlocked yes)
			(layer "F.Fab")
			(hide yes)
			(effects
				(font
					(size 2.54 2.54)
					(thickness 0.381)
				)
			)
		)
		(property "Device Type" "R402H16"
			(at 0.064008 -6.203696 270)
			(unlocked yes)
			(layer "F.Fab")
			(hide yes)
			(effects
				(font
					(size 2.54 2.54)
					(thickness 0.381)
				)
			)
		)
		(duplicate_pad_numbers_are_jumpers no)
		(fp_line
			(start -0.508 -0.9398)
			(end -0.508 0.9398)
			(stroke
				(width 0.1524)
				(type default)
			)
			(layer "F.SilkS")
		)
		(fp_line
			(start 0.508 -0.9398)
			(end -0.508 -0.9398)
			(stroke
				(width 0.1524)
				(type default)
			)
			(layer "F.SilkS")
		)
		(fp_rect
			(start -0.508 0.9398)
			(end 0.508 -0.9398)
			(stroke
				(width 0)
				(type default)
			)
			(fill no)
			(layer "F.CrtYd")
		)
		(fp_rect
			(start -0.508 0.9398)
			(end 0.508 -0.9398)
			(stroke
				(width 0)
				(type default)
			)
			(fill no)
			(layer "F.Fab")
		)
		(pad "1" smd custom
			(at 0 -0.4445 270)
			(size 0.1397 0.1397)
			(layers "F.Cu" "F.Mask" "F.Paste")
			(net "P3V3_STBY_B")
			(options
				(clearance outline)
				(anchor circle)
			)
			(primitives
				(gr_poly
					(pts
						(arc
							(start -0.1778 -0.2794)
							(mid -0.249642 -0.249642)
							(end -0.2794 -0.1778)
						)
						(arc
							(start -0.2794 0.1778)
							(mid -0.249642 0.249642)
							(end -0.1778 0.2794)
						)
						(arc
							(start 0.1778 0.2794)
							(mid 0.249642 0.249642)
							(end 0.2794 0.1778)
						)
						(arc
							(start 0.2794 -0.1778)
							(mid 0.249642 -0.249642)
							(end 0.1778 -0.2794)
						)
					)
					(width 0)
					(fill yes)
				)
			)
		)
		(pad "2" smd custom
			(at 0 0.4445 270)
			(size 0.1397 0.1397)
			(layers "F.Cu" "F.Mask" "F.Paste")
			(net "SYS_RESET_BTN_B_N_R")
			(options
				(clearance outline)
				(anchor circle)
			)
			(primitives
				(gr_poly
					(pts
						(arc
							(start -0.1778 -0.2794)
							(mid -0.249642 -0.249642)
							(end -0.2794 -0.1778)
						)
						(arc
							(start -0.2794 0.1778)
							(mid -0.249642 0.249642)
							(end -0.1778 0.2794)
						)
						(arc
							(start 0.1778 0.2794)
							(mid 0.249642 0.249642)
							(end 0.2794 0.1778)
						)
						(arc
							(start 0.2794 -0.1778)
							(mid 0.249642 -0.249642)
							(end 0.1778 -0.2794)
						)
					)
					(width 0)
					(fill yes)
				)
			)
		)
	)
	(footprint ""
		(layer "F.Cu")
		(at 20.1168 -18.2372)
		(property "Reference" "R63"
			(at 0 0 0)
			(layer "F.SilkS")
			(hide yes)
			(effects
				(font
					(size 1.27 1.27)
				)
			)
		)
		(property "Value" "4K7R2F-GP"
			(at 0.064008 -3.993896 0)
			(unlocked yes)
			(layer "F.Fab")
			(hide yes)
			(effects
				(font
					(size 1.016 1.016)
					(thickness 0.1524)
				)
			)
		)
		(property "Device Type" "R402H16"
			(at 0.064008 -5.517896 0)
			(unlocked yes)
			(layer "F.Fab")
			(hide yes)
			(effects
				(font
					(size 1.016 1.016)
					(thickness 0.1524)
				)
			)
		)
		(duplicate_pad_numbers_are_jumpers no)
		(fp_line
			(start -0.508 -0.9398)
			(end -0.508 0.9398)
			(stroke
				(width 0.1524)
				(type default)
			)
			(layer "F.SilkS")
		)
		(fp_line
			(start 0.508 -0.9398)
			(end -0.508 -0.9398)
			(stroke
				(width 0.1524)
				(type default)
			)
			(layer "F.SilkS")
		)
		(fp_rect
			(start -0.508 0.9398)
			(end 0.508 -0.9398)
			(stroke
				(width 0)
				(type default)
			)
			(fill no)
			(layer "F.CrtYd")
		)
		(fp_rect
			(start -0.508 0.9398)
			(end 0.508 -0.9398)
			(stroke
				(width 0)
				(type default)
			)
			(fill no)
			(layer "F.Fab")
		)
		(pad "1" smd custom
			(at 0 -0.4445)
			(size 0.1397 0.1397)
			(layers "F.Cu" "F.Mask" "F.Paste")
			(net "P3V3_STBY_A")
			(options
				(clearance outline)
				(anchor circle)
			)
			(primitives
				(gr_poly
					(pts
						(arc
							(start -0.1778 -0.2794)
							(mid -0.249642 -0.249642)
							(end -0.2794 -0.1778)
						)
						(arc
							(start -0.2794 0.1778)
							(mid -0.249642 0.249642)
							(end -0.1778 0.2794)
						)
						(arc
							(start 0.1778 0.2794)
							(mid 0.249642 0.249642)
							(end 0.2794 0.1778)
						)
						(arc
							(start 0.2794 -0.1778)
							(mid 0.249642 -0.249642)
							(end 0.1778 -0.2794)
						)
					)
					(width 0)
					(fill yes)
				)
			)
		)
		(pad "2" smd custom
			(at 0 0.4445)
			(size 0.1397 0.1397)
			(layers "F.Cu" "F.Mask" "F.Paste")
			(net "TCA9555_A_A1")
			(options
				(clearance outline)
				(anchor circle)
			)
			(primitives
				(gr_poly
					(pts
						(arc
							(start -0.1778 -0.2794)
							(mid -0.249642 -0.249642)
							(end -0.2794 -0.1778)
						)
						(arc
							(start -0.2794 0.1778)
							(mid -0.249642 0.249642)
							(end -0.1778 0.2794)
						)
						(arc
							(start 0.1778 0.2794)
							(mid 0.249642 0.249642)
							(end 0.2794 0.1778)
						)
						(arc
							(start 0.2794 -0.1778)
							(mid 0.249642 -0.249642)
							(end 0.1778 -0.2794)
						)
					)
					(width 0)
					(fill yes)
				)
			)
		)
	)
	(footprint ""
		(layer "F.Cu")
		(at 27.686762 -10.23239)
		(property "Reference" "U19"
			(at 0 0 0)
			(layer "F.SilkS")
			(hide yes)
			(effects
				(font
					(size 1.27 1.27)
				)
			)
		)
		(property "Value" "SN74LVC1G74DCUT-GP"
			(at 0 -11.1252 0)
			(unlocked yes)
			(layer "F.Fab")
			(hide yes)
			(effects
				(font
					(size 1.016 1.016)
					(thickness 0.1524)
				)
			)
		)
		(property "Device Type" "SSOIC8-4H36"
			(at 0 -12.6492 0)
			(unlocked yes)
			(layer "F.Fab")
			(hide yes)
			(effects
				(font
					(size 1.016 1.016)
					(thickness 0.1524)
				)
			)
		)
		(duplicate_pad_numbers_are_jumpers no)
		(fp_line
			(start -1.2954 0.4572)
			(end -1.2954 2.159)
			(stroke
				(width 0.4064)
				(type default)
			)
			(layer "F.SilkS")
		)
		(fp_line
			(start -1.2573 -2.1844)
			(end 1.2573 -2.1844)
			(stroke
				(width 0.1524)
				(type default)
			)
			(layer "F.SilkS")
		)
		(fp_line
			(start -1.2573 -0.3556)
			(end -1.2192 -0.3556)
			(stroke
				(width 0.1524)
				(type default)
			)
			(layer "F.SilkS")
		)
		(fp_line
			(start -1.2573 2.1844)
			(end -1.2573 -2.1844)
			(stroke
				(width 0.1524)
				(type default)
			)
			(layer "F.SilkS")
		)
		(fp_line
			(start -1.2192 -0.3556)
			(end -0.9017 -0.0381)
			(stroke
				(width 0.1524)
				(type default)
			)
			(layer "F.SilkS")
		)
		(fp_line
			(start -1.2065 0.2667)
			(end -1.27 0.2667)
			(stroke
				(width 0.1524)
				(type default)
			)
			(layer "F.SilkS")
		)
		(fp_line
			(start -0.9017 -0.0381)
			(end -1.2065 0.2667)
			(stroke
				(width 0.1524)
				(type default)
			)
			(layer "F.SilkS")
		)
		(fp_line
			(start 1.2573 -2.1844)
			(end 1.2573 2.1844)
			(stroke
				(width 0.1524)
				(type default)
			)
			(layer "F.SilkS")
		)
		(fp_line
			(start 1.2573 2.1844)
			(end -1.2573 2.1844)
			(stroke
				(width 0.1524)
				(type default)
			)
			(layer "F.SilkS")
		)
		(fp_poly
			(pts
				(xy -1.5113 2.4384) (xy 1.5113 2.4384) (xy 1.5113 -2.4384) (xy -1.5113 -2.4384)
			)
			(stroke
				(width 0)
				(type default)
			)
			(fill no)
			(layer "F.CrtYd")
		)
		(fp_poly
			(pts
				(xy -1.5113 -2.4384) (xy 1.5113 -2.4384) (xy 1.5113 2.4384) (xy -1.5113 2.4384)
			)
			(stroke
				(width 0)
				(type default)
			)
			(fill no)
			(layer "F.Fab")
		)
		(pad "1" smd rect
			(at -0.75057 1.1684)
			(size 0.3048 1.524)
			(layers "F.Cu" "F.Mask" "F.Paste")
			(net "DEBUG_HDR_A_UART_SEL")
		)
		(pad "2" smd rect
			(at -0.25019 1.1684)
			(size 0.3048 1.524)
			(layers "F.Cu" "F.Mask" "F.Paste")
			(net "D_FLIP_A_D")
		)
		(pad "3" smd rect
			(at 0.25019 1.1684)
			(size 0.3048 1.524)
			(layers "F.Cu" "F.Mask" "F.Paste")
			(net "D_FLIP_A_Q#")
		)
		(pad "4" smd rect
			(at 0.75057 1.1684)
			(size 0.3048 1.524)
			(layers "F.Cu" "F.Mask" "F.Paste")
			(net "GND")
		)
		(pad "5" smd rect
			(at 0.75057 -1.1684)
			(size 0.3048 1.524)
			(layers "F.Cu" "F.Mask" "F.Paste")
			(net "UART_SEL_A_MUX")
		)
		(pad "6" smd rect
			(at 0.25019 -1.1684)
			(size 0.3048 1.524)
			(layers "F.Cu" "F.Mask" "F.Paste")
			(net "D_FLIP_CLR_A#")
		)
		(pad "7" smd rect
			(at -0.25019 -1.1684)
			(size 0.3048 1.524)
			(layers "F.Cu" "F.Mask" "F.Paste")
			(net "D_FLIP_PRE_A#")
		)
		(pad "8" smd rect
			(at -0.75057 -1.1684)
			(size 0.3048 1.524)
			(layers "F.Cu" "F.Mask" "F.Paste")
			(net "P3V3_STBY_A")
		)
	)
	(footprint ""
		(layer "F.Cu")
		(at 41.4274 -12.2428 -90)
		(property "Reference" "C26"
			(at 0 0 270)
			(layer "F.SilkS")
			(hide yes)
			(effects
				(font
					(size 1.27 1.27)
				)
			)
		)
		(property "Value" "SCD1U16V2KX-3GP"
			(at 1.1811 -2.7051 270)
			(unlocked yes)
			(layer "F.Fab")
			(hide yes)
			(effects
				(font
					(size 1.016 1.016)
					(thickness 0.1524)
				)
			)
		)
		(property "Device Type" "C402H22"
			(at 1.1811 -4.2291 270)
			(unlocked yes)
			(layer "F.Fab")
			(hide yes)
			(effects
				(font
					(size 1.016 1.016)
					(thickness 0.1524)
				)
			)
		)
		(duplicate_pad_numbers_are_jumpers no)
		(fp_rect
			(start -0.4318 0.9525)
			(end 0.4318 -0.9525)
			(stroke
				(width 0)
				(type default)
			)
			(fill no)
			(layer "F.CrtYd")
		)
		(fp_rect
			(start -0.4318 0.9525)
			(end 0.4318 -0.9525)
			(stroke
				(width 0)
				(type default)
			)
			(fill no)
			(layer "F.Fab")
		)
		(pad "1" smd custom
			(at 0 -0.4445 270)
			(size 0.1524 0.1524)
			(layers "F.Cu" "F.Mask" "F.Paste")
			(net "P3V3_STBY_B")
			(options
				(clearance outline)
				(anchor circle)
			)
			(primitives
				(gr_poly
					(pts
						(arc
							(start 0.3048 -0.2032)
							(mid 0.275042 -0.275042)
							(end 0.2032 -0.3048)
						)
						(arc
							(start -0.2032 -0.3048)
							(mid -0.275042 -0.275042)
							(end -0.3048 -0.2032)
						)
						(arc
							(start -0.3048 0.2032)
							(mid -0.275042 0.275042)
							(end -0.2032 0.3048)
						)
						(arc
							(start 0.2032 0.3048)
							(mid 0.275042 0.275042)
							(end 0.3048 0.2032)
						)
					)
					(width 0)
					(fill yes)
				)
			)
		)
		(pad "2" smd custom
			(at 0 0.4445 270)
			(size 0.1524 0.1524)
			(layers "F.Cu" "F.Mask" "F.Paste")
			(net "GND")
			(options
				(clearance outline)
				(anchor circle)
			)
			(primitives
				(gr_poly
					(pts
						(arc
							(start 0.3048 -0.2032)
							(mid 0.275042 -0.275042)
							(end 0.2032 -0.3048)
						)
						(arc
							(start -0.2032 -0.3048)
							(mid -0.275042 -0.275042)
							(end -0.3048 -0.2032)
						)
						(arc
							(start -0.3048 0.2032)
							(mid -0.275042 0.275042)
							(end -0.2032 0.3048)
						)
						(arc
							(start 0.2032 0.3048)
							(mid 0.275042 0.275042)
							(end 0.3048 0.2032)
						)
					)
					(width 0)
					(fill yes)
				)
			)
		)
	)
	(footprint ""
		(layer "F.Cu")
		(at 30.0482 -6.9596 90)
		(property "Reference" "C34"
			(at 0 0 90)
			(layer "F.SilkS")
			(hide yes)
			(effects
				(font
					(size 1.27 1.27)
				)
			)
		)
		(property "Value" "SCD1U16V2KX-3GP"
			(at 1.1811 -2.7051 90)
			(unlocked yes)
			(layer "F.Fab")
			(hide yes)
			(effects
				(font
					(size 1.016 1.016)
					(thickness 0.1524)
				)
			)
		)
		(property "Device Type" "C402H22"
			(at 1.1811 -4.2291 90)
			(unlocked yes)
			(layer "F.Fab")
			(hide yes)
			(effects
				(font
					(size 1.016 1.016)
					(thickness 0.1524)
				)
			)
		)
		(duplicate_pad_numbers_are_jumpers no)
		(fp_rect
			(start -0.4318 0.9525)
			(end 0.4318 -0.9525)
			(stroke
				(width 0)
				(type default)
			)
			(fill no)
			(layer "F.CrtYd")
		)
		(fp_rect
			(start -0.4318 0.9525)
			(end 0.4318 -0.9525)
			(stroke
				(width 0)
				(type default)
			)
			(fill no)
			(layer "F.Fab")
		)
		(pad "1" smd custom
			(at 0 -0.4445 90)
			(size 0.1524 0.1524)
			(layers "F.Cu" "F.Mask" "F.Paste")
			(net "D_FLIP_CLR_B#")
			(options
				(clearance outline)
				(anchor circle)
			)
			(primitives
				(gr_poly
					(pts
						(arc
							(start 0.3048 -0.2032)
							(mid 0.275042 -0.275042)
							(end 0.2032 -0.3048)
						)
						(arc
							(start -0.2032 -0.3048)
							(mid -0.275042 -0.275042)
							(end -0.3048 -0.2032)
						)
						(arc
							(start -0.3048 0.2032)
							(mid -0.275042 0.275042)
							(end -0.2032 0.3048)
						)
						(arc
							(start 0.2032 0.3048)
							(mid 0.275042 0.275042)
							(end 0.3048 0.2032)
						)
					)
					(width 0)
					(fill yes)
				)
			)
		)
		(pad "2" smd custom
			(at 0 0.4445 90)
			(size 0.1524 0.1524)
			(layers "F.Cu" "F.Mask" "F.Paste")
			(net "GND")
			(options
				(clearance outline)
				(anchor circle)
			)
			(primitives
				(gr_poly
					(pts
						(arc
							(start 0.3048 -0.2032)
							(mid 0.275042 -0.275042)
							(end 0.2032 -0.3048)
						)
						(arc
							(start -0.2032 -0.3048)
							(mid -0.275042 -0.275042)
							(end -0.3048 -0.2032)
						)
						(arc
							(start -0.3048 0.2032)
							(mid -0.275042 0.275042)
							(end -0.2032 0.3048)
						)
						(arc
							(start 0.2032 0.3048)
							(mid 0.275042 0.275042)
							(end 0.3048 0.2032)
						)
					)
					(width 0)
					(fill yes)
				)
			)
		)
	)
)
